(kicad_pcb
	(version 20260206)
	(generator "pcbnew")
	(generator_version "10.0")
	(general
		(thickness 1.6)
		(legacy_teardrops no)
	)
	(paper "A4")
	(title_block
		(title "v1-tray-backplane — T6M_tray_BP_c_1023_1120.brd")
		(comment 1 "Open CloudServer (Microsoft) / footprints 156-158 of 170")
	)
	(layers
		(0 "F.Cu" signal "TOP")
		(4 "In1.Cu" signal "GND")
		(6 "In2.Cu" signal "IN1")
		(8 "In3.Cu" signal "VCC")
		(10 "In4.Cu" signal "VCC1")
		(12 "In5.Cu" signal "IN2")
		(14 "In6.Cu" signal "GND1")
		(2 "B.Cu" signal "BOTTOM")
		(9 "F.Adhes" user "F.Adhesive")
		(11 "B.Adhes" user "B.Adhesive")
		(13 "F.Paste" user "Package Geometry/Pastemask Top")
		(15 "B.Paste" user "Package Geometry/Pastemask Bottom")
		(5 "F.SilkS" user "Ref Des/Silkscreen Top")
		(7 "B.SilkS" user "Ref Des/Silkscreen Bottom")
		(1 "F.Mask" user "Board Geometry/Soldermask Top")
		(3 "B.Mask" user "Board Geometry/Soldermask Bottom")
		(17 "Dwgs.User" user "User.Drawings")
		(19 "Cmts.User" user "User.Comments")
		(21 "Eco1.User" user "User.Eco1")
		(23 "Eco2.User" user "User.Eco2")
		(25 "Edge.Cuts" user "Board Geometry/Outline")
		(27 "Margin" user)
		(31 "F.CrtYd" user "Package Geometry/Place Bound Top")
		(29 "B.CrtYd" user "Package Geometry/Place Bound Bottom")
		(35 "F.Fab" user "Ref Des/Assembly Top")
		(33 "B.Fab" user "Ref Des/Assembly Bottom")
	)
	(footprint ""
		(layer "F.Cu")
		(at 191.494918 -28.4099 180)
		(property "Reference" "U1"
			(at -9.3091 -9.331452 0)
			(unlocked yes)
			(layer "F.SilkS")
			(effects
				(font
					(size 0.7874 0.5842)
					(thickness 0.1524)
				)
				(justify left)
			)
		)
		(property "Value" ""
			(at 0 0 180)
			(layer "F.Fab")
			(effects
				(font
					(size 1.27 1.27)
				)
			)
		)
		(duplicate_pad_numbers_are_jumpers no)
		(fp_line
			(start 6.949948 8.32993)
			(end 6.949948 5.7912)
			(stroke
				(width 0.1524)
				(type default)
			)
			(layer "F.SilkS")
		)
		(fp_line
			(start 6.949948 4.572)
			(end 6.949948 0)
			(stroke
				(width 0.1524)
				(type default)
			)
			(layer "F.SilkS")
		)
		(fp_line
			(start 6.949948 -3.670046)
			(end 0 -3.670046)
			(stroke
				(width 0.1524)
				(type default)
			)
			(layer "F.SilkS")
		)
		(fp_line
			(start 0 -3.670046)
			(end -6.949948 -3.670046)
			(stroke
				(width 0.1524)
				(type default)
			)
			(layer "F.SilkS")
		)
		(fp_line
			(start -6.949948 8.32993)
			(end 6.949948 8.32993)
			(stroke
				(width 0.1524)
				(type default)
			)
			(layer "F.SilkS")
		)
		(fp_line
			(start -6.949948 5.7912)
			(end -6.949948 8.32993)
			(stroke
				(width 0.1524)
				(type default)
			)
			(layer "F.SilkS")
		)
		(fp_line
			(start -6.949948 0)
			(end -6.949948 4.5466)
			(stroke
				(width 0.1524)
				(type default)
			)
			(layer "F.SilkS")
		)
		(fp_line
			(start -6.949948 -3.670046)
			(end -6.949948 0)
			(stroke
				(width 0.1524)
				(type default)
			)
			(layer "F.SilkS")
		)
		(fp_poly
			(pts
				(xy -6.9596 0) (xy -8.7376 1.016) (xy -8.7376 -1.016)
			)
			(stroke
				(width 0)
				(type default)
			)
			(fill yes)
			(layer "F.SilkS")
		)
		(fp_poly
			(pts
				(arc
					(start 4.933188 5.180076)
					(mid 7.066788 5.180076)
					(end 4.933188 5.180076)
				)
			)
			(stroke
				(width 0)
				(type default)
			)
			(fill no)
			(layer "B.CrtYd")
		)
		(fp_poly
			(pts
				(arc
					(start -7.06755 5.180076)
					(mid -4.932426 5.180076)
					(end -7.06755 5.180076)
				)
			)
			(stroke
				(width 0)
				(type default)
			)
			(fill no)
			(layer "B.CrtYd")
		)
		(fp_poly
			(pts
				(xy -6.949948 8.32993) (xy 6.949948 8.32993) (xy 6.949948 -3.670046) (xy -6.949948 -3.670046)
			)
			(stroke
				(width 0)
				(type default)
			)
			(fill no)
			(layer "F.CrtYd")
		)
		(fp_line
			(start 6.949948 8.32993)
			(end 6.949948 -3.670046)
			(stroke
				(width 0.1)
				(type default)
			)
			(layer "F.Fab")
		)
		(fp_line
			(start 6.949948 -3.670046)
			(end -6.949948 -3.670046)
			(stroke
				(width 0.1)
				(type default)
			)
			(layer "F.Fab")
		)
		(fp_line
			(start -6.700012 0)
			(end -6.949948 0)
			(stroke
				(width 0.1)
				(type default)
			)
			(layer "F.Fab")
		)
		(fp_line
			(start -6.949948 8.32993)
			(end 6.949948 8.32993)
			(stroke
				(width 0.1)
				(type default)
			)
			(layer "F.Fab")
		)
		(fp_line
			(start -6.949948 0)
			(end -6.949948 8.32993)
			(stroke
				(width 0.1)
				(type default)
			)
			(layer "F.Fab")
		)
		(fp_line
			(start -6.949948 -3.670046)
			(end -6.949948 0)
			(stroke
				(width 0.1)
				(type default)
			)
			(layer "F.Fab")
		)
		(fp_poly
			(pts
				(xy -6.9596 0) (xy -8.7376 1.016) (xy -8.7376 -1.016)
			)
			(stroke
				(width 0)
				(type default)
			)
			(fill yes)
			(layer "F.Fab")
		)
		(fp_text user "A13"
			(at 9.481566 0.837184 90)
			(unlocked yes)
			(layer "F.SilkS")
			(effects
				(font
					(size 0.7874 0.5842)
					(thickness 0.1524)
				)
				(justify left)
			)
		)
		(fp_text user "B13"
			(at 9.42594 -3.176016 90)
			(unlocked yes)
			(layer "F.SilkS")
			(effects
				(font
					(size 0.7874 0.5842)
					(thickness 0.1524)
				)
				(justify left)
			)
		)
		(fp_text user "A1"
			(at -11.85418 1.438148 0)
			(unlocked yes)
			(layer "F.SilkS")
			(effects
				(font
					(size 0.7874 0.5842)
					(thickness 0.1524)
				)
				(justify left)
			)
		)
		(fp_text user "B1"
			(at -11.85418 -3.367278 0)
			(unlocked yes)
			(layer "F.SilkS")
			(effects
				(font
					(size 0.7874 0.5842)
					(thickness 0.1524)
				)
				(justify left)
			)
		)
		(fp_text user "A13"
			(at 7.360666 -0.091948 180)
			(unlocked yes)
			(layer "F.Fab")
			(effects
				(font
					(size 0.7874 0.5842)
					(thickness 0.000001)
				)
				(justify left)
			)
		)
		(fp_text user "B13"
			(at 7.360666 -2.601722 180)
			(unlocked yes)
			(layer "F.Fab")
			(effects
				(font
					(size 0.7874 0.5842)
					(thickness 0.000001)
				)
				(justify left)
			)
		)
		(fp_text user "A1"
			(at -8.609584 1.330452 180)
			(unlocked yes)
			(layer "F.Fab")
			(effects
				(font
					(size 0.7874 0.5842)
					(thickness 0.000001)
				)
				(justify left)
			)
		)
		(fp_text user "B1"
			(at -8.685784 -2.601722 180)
			(unlocked yes)
			(layer "F.Fab")
			(effects
				(font
					(size 0.7874 0.5842)
					(thickness 0.000001)
				)
				(justify left)
			)
		)
		(pad "" np_thru_hole circle
			(at -5.999988 5.180076 180)
			(size 1.6002 1.6002)
			(drill 1.6002)
			(layers "*.Cu" "*.Mask")
			(clearance 0.381)
			(thermal_gap 0.381)
		)
		(pad "" np_thru_hole circle
			(at 5.999988 5.180076 180)
			(size 1.6002 1.6002)
			(drill 1.6002)
			(layers "*.Cu" "*.Mask")
			(clearance 0.381)
			(thermal_gap 0.381)
		)
		(pad "A1" smd rect
			(at -4.59994 0 180)
			(size 0.381 1.8542)
			(layers "F.Cu" "F.Mask" "F.Paste")
			(net "GND")
		)
		(pad "A2" smd rect
			(at -3.800094 0 180)
			(size 0.381 1.8542)
			(layers "F.Cu" "F.Mask" "F.Paste")
			(net "SAS_BLAD1_RX1_P")
		)
		(pad "A3" smd rect
			(at -2.999994 0 180)
			(size 0.381 1.8542)
			(layers "F.Cu" "F.Mask" "F.Paste")
			(net "SAS_BLAD1_RX1_N")
		)
		(pad "A4" smd rect
			(at -2.199894 0 180)
			(size 0.381 1.8542)
			(layers "F.Cu" "F.Mask" "F.Paste")
			(net "GND")
		)
		(pad "A5" smd rect
			(at -1.400048 0 180)
			(size 0.381 1.8542)
			(layers "F.Cu" "F.Mask" "F.Paste")
			(net "SAS_BLAD1_RX2_P")
		)
		(pad "A6" smd rect
			(at -0.599948 0 180)
			(size 0.381 1.8542)
			(layers "F.Cu" "F.Mask" "F.Paste")
			(net "SAS_BLAD1_RX2_N")
		)
		(pad "A7" smd rect
			(at 0.199898 0 180)
			(size 0.381 1.8542)
			(layers "F.Cu" "F.Mask" "F.Paste")
			(net "GND")
		)
		(pad "A8" smd rect
			(at 0.999998 0 180)
			(size 0.381 1.8542)
			(layers "F.Cu" "F.Mask" "F.Paste")
			(net "SAS_BLAD1_RX3_P")
		)
		(pad "A9" smd rect
			(at 1.800098 0 180)
			(size 0.381 1.8542)
			(layers "F.Cu" "F.Mask" "F.Paste")
			(net "SAS_BLAD1_RX3_N")
		)
		(pad "A10" smd rect
			(at 2.599944 0 180)
			(size 0.381 1.8542)
			(layers "F.Cu" "F.Mask" "F.Paste")
			(net "GND")
		)
		(pad "A11" smd rect
			(at 3.400044 0 180)
			(size 0.381 1.8542)
			(layers "F.Cu" "F.Mask" "F.Paste")
			(net "SAS_BLAD1_RX4_P")
		)
		(pad "A12" smd rect
			(at 4.19989 0 180)
			(size 0.381 1.8542)
			(layers "F.Cu" "F.Mask" "F.Paste")
			(net "SAS_BLAD1_RX4_N")
		)
		(pad "A13" smd rect
			(at 4.99999 0 180)
			(size 0.381 1.8542)
			(layers "F.Cu" "F.Mask" "F.Paste")
			(net "GND")
		)
		(pad "B1" smd rect
			(at -4.99999 -2.510028 180)
			(size 0.381 1.8542)
			(layers "F.Cu" "F.Mask" "F.Paste")
			(net "GND")
		)
		(pad "B2" smd rect
			(at -4.19989 -2.510028 180)
			(size 0.381 1.8542)
			(layers "F.Cu" "F.Mask" "F.Paste")
			(net "SAS_BLAD1_TX1_P")
		)
		(pad "B3" smd rect
			(at -3.400044 -2.510028 180)
			(size 0.381 1.8542)
			(layers "F.Cu" "F.Mask" "F.Paste")
			(net "SAS_BLAD1_TX1_N")
		)
		(pad "B4" smd rect
			(at -2.599944 -2.510028 180)
			(size 0.381 1.8542)
			(layers "F.Cu" "F.Mask" "F.Paste")
			(net "GND")
		)
		(pad "B5" smd rect
			(at -1.800098 -2.510028 180)
			(size 0.381 1.8542)
			(layers "F.Cu" "F.Mask" "F.Paste")
			(net "SAS_BLAD1_TX2_P")
		)
		(pad "B6" smd rect
			(at -0.999998 -2.510028 180)
			(size 0.381 1.8542)
			(layers "F.Cu" "F.Mask" "F.Paste")
			(net "SAS_BLAD1_TX2_N")
		)
		(pad "B7" smd rect
			(at -0.199898 -2.510028 180)
			(size 0.381 1.8542)
			(layers "F.Cu" "F.Mask" "F.Paste")
			(net "GND")
		)
		(pad "B8" smd rect
			(at 0.599948 -2.510028 180)
			(size 0.381 1.8542)
			(layers "F.Cu" "F.Mask" "F.Paste")
			(net "SAS_BLAD1_TX3_P")
		)
		(pad "B9" smd rect
			(at 1.400048 -2.510028 180)
			(size 0.381 1.8542)
			(layers "F.Cu" "F.Mask" "F.Paste")
			(net "SAS_BLAD1_TX3_N")
		)
		(pad "B10" smd rect
			(at 2.199894 -2.510028 180)
			(size 0.381 1.8542)
			(layers "F.Cu" "F.Mask" "F.Paste")
			(net "GND")
		)
		(pad "B11" smd rect
			(at 2.999994 -2.510028 180)
			(size 0.381 1.8542)
			(layers "F.Cu" "F.Mask" "F.Paste")
			(net "SAS_BLAD1_TX4_P")
		)
		(pad "B12" smd rect
			(at 3.800094 -2.510028 180)
			(size 0.381 1.8542)
			(layers "F.Cu" "F.Mask" "F.Paste")
			(net "SAS_BLAD1_TX4_N")
		)
		(pad "B13" smd rect
			(at 4.59994 -2.510028 180)
			(size 0.381 1.8542)
			(layers "F.Cu" "F.Mask" "F.Paste")
			(net "GND")
		)
		(zone
			(layer "F.Cu")
			(hatch none 0.5)
			(connect_pads
				(clearance 0)
			)
			(min_thickness 0.25)
			(keepout
				(tracks not_allowed)
				(vias allowed)
				(pads allowed)
				(copperpour not_allowed)
				(footprints allowed)
			)
			(placement
				(enabled no)
				(sheetname "")
			)
			(fill
				(thermal_gap 0.5)
				(thermal_bridge_width 0.5)
				(island_removal_mode 0)
			)
			(polygon
				(pts
					(xy 186.414918 -36.73983) (xy 184.574942 -36.73983) (xy 184.574942 -35.279838) (xy 186.414918 -35.279838)
				)
			)
		)
		(zone
			(layer "F.Cu")
			(hatch none 0.5)
			(connect_pads
				(clearance 0)
			)
			(min_thickness 0.25)
			(keepout
				(tracks not_allowed)
				(vias allowed)
				(pads allowed)
				(copperpour not_allowed)
				(footprints allowed)
			)
			(placement
				(enabled no)
				(sheetname "")
			)
			(fill
				(thermal_gap 0.5)
				(thermal_bridge_width 0.5)
				(island_removal_mode 0)
			)
			(polygon
				(pts
					(xy 198.414894 -36.73983) (xy 196.574918 -36.73983) (xy 196.574918 -35.279838) (xy 198.414894 -35.279838)
				)
			)
		)
		(zone
			(layers "F.Cu" "B.Cu" "In1.Cu" "In2.Cu" "In3.Cu" "In4.Cu" "In5.Cu" "In6.Cu")
			(hatch none 0.5)
			(connect_pads
				(clearance 0)
			)
			(min_thickness 0.25)
			(keepout
				(tracks not_allowed)
				(vias allowed)
				(pads allowed)
				(copperpour not_allowed)
				(footprints allowed)
			)
			(placement
				(enabled no)
				(sheetname "")
			)
			(fill
				(thermal_gap 0.5)
				(thermal_bridge_width 0.5)
				(island_removal_mode 0)
			)
			(polygon
				(pts
					(arc
						(start 186.713876 -33.589976)
						(mid 184.275984 -33.589976)
						(end 186.713876 -33.589976)
					)
				)
			)
		)
		(zone
			(layers "F.Cu" "B.Cu" "In1.Cu" "In2.Cu" "In3.Cu" "In4.Cu" "In5.Cu" "In6.Cu")
			(hatch none 0.5)
			(connect_pads
				(clearance 0)
			)
			(min_thickness 0.25)
			(keepout
				(tracks not_allowed)
				(vias allowed)
				(pads allowed)
				(copperpour not_allowed)
				(footprints allowed)
			)
			(placement
				(enabled no)
				(sheetname "")
			)
			(fill
				(thermal_gap 0.5)
				(thermal_bridge_width 0.5)
				(island_removal_mode 0)
			)
			(polygon
				(pts
					(arc
						(start 198.714614 -33.589976)
						(mid 196.275198 -33.589976)
						(end 198.714614 -33.589976)
					)
				)
			)
		)
	)
	(footprint ""
		(layer "F.Cu")
		(at 310.308752 -28.966922 180)
		(property "Reference" "R55"
			(at 6.801104 0.984504 0)
			(unlocked yes)
			(layer "F.SilkS")
			(effects
				(font
					(size 0.7874 0.5842)
					(thickness 0.1524)
				)
				(justify left)
			)
		)
		(property "Value" ""
			(at 0 0 180)
			(layer "F.Fab")
			(effects
				(font
					(size 1.27 1.27)
				)
			)
		)
		(duplicate_pad_numbers_are_jumpers no)
		(fp_line
			(start 0.7874 0.4064)
			(end -0.7874 0.4064)
			(stroke
				(width 0.1524)
				(type default)
			)
			(layer "F.SilkS")
		)
		(fp_line
			(start 0.7874 -0.4064)
			(end 0.7874 0.4064)
			(stroke
				(width 0.1524)
				(type default)
			)
			(layer "F.SilkS")
		)
		(fp_line
			(start -0.7874 0.4064)
			(end -0.7874 -0.4064)
			(stroke
				(width 0.1524)
				(type default)
			)
			(layer "F.SilkS")
		)
		(fp_line
			(start -0.7874 -0.4064)
			(end 0.7874 -0.4064)
			(stroke
				(width 0.1524)
				(type default)
			)
			(layer "F.SilkS")
		)
		(fp_poly
			(pts
				(xy -0.508 0.2794) (xy -0.508 0.2286) (xy -0.635 0.2286) (xy -0.635 -0.254) (xy -0.5334 -0.254)
				(xy -0.5334 -0.2794) (xy 0.5334 -0.2794) (xy 0.5334 -0.254) (xy 0.635 -0.254) (xy 0.635 0.254) (xy 0.5334 0.254)
				(xy 0.5334 0.2794)
			)
			(stroke
				(width 0)
				(type default)
			)
			(fill no)
			(layer "F.CrtYd")
		)
		(pad "1" smd rect
			(at 0.40005 0 180)
			(size 0.4572 0.508)
			(layers "F.Cu" "F.Mask" "F.Paste")
			(net "GND")
		)
		(pad "2" smd rect
			(at -0.40005 0 180)
			(size 0.4572 0.508)
			(layers "F.Cu" "F.Mask" "F.Paste")
			(net "ENET10G_4_TX_DIS")
		)
	)
	(footprint ""
		(layer "F.Cu")
		(at 117.31244 -21.08581)
		(property "Reference" "R46"
			(at -61.341 4.988052 0)
			(unlocked yes)
			(layer "F.SilkS")
			(effects
				(font
					(size 0.7874 0.5842)
					(thickness 0.1524)
				)
				(justify left)
			)
		)
		(property "Value" ""
			(at 0 0 0)
			(layer "F.Fab")
			(effects
				(font
					(size 1.27 1.27)
				)
			)
		)
		(duplicate_pad_numbers_are_jumpers no)
		(fp_line
			(start -0.7874 -0.4064)
			(end 0.7874 -0.4064)
			(stroke
				(width 0.1524)
				(type default)
			)
			(layer "F.SilkS")
		)
		(fp_line
			(start -0.7874 0.4064)
			(end -0.7874 -0.4064)
			(stroke
				(width 0.1524)
				(type default)
			)
			(layer "F.SilkS")
		)
		(fp_line
			(start 0.7874 -0.4064)
			(end 0.7874 0.4064)
			(stroke
				(width 0.1524)
				(type default)
			)
			(layer "F.SilkS")
		)
		(fp_line
			(start 0.7874 0.4064)
			(end -0.7874 0.4064)
			(stroke
				(width 0.1524)
				(type default)
			)
			(layer "F.SilkS")
		)
		(fp_poly
			(pts
				(xy -0.508 0.2794) (xy -0.508 0.2286) (xy -0.635 0.2286) (xy -0.635 -0.254) (xy -0.5334 -0.254)
				(xy -0.5334 -0.2794) (xy 0.5334 -0.2794) (xy 0.5334 -0.254) (xy 0.635 -0.254) (xy 0.635 0.254) (xy 0.5334 0.254)
				(xy 0.5334 0.2794)
			)
			(stroke
				(width 0)
				(type default)
			)
			(fill no)
			(layer "F.CrtYd")
		)
		(pad "1" smd rect
			(at 0.40005 0)
			(size 0.4572 0.508)
			(layers "F.Cu" "F.Mask" "F.Paste")
			(net "GND")
		)
		(pad "2" smd rect
			(at -0.40005 0)
			(size 0.4572 0.508)
			(layers "F.Cu" "F.Mask" "F.Paste")
			(net "ENET10G_2_TX_FAULT")
		)
	)
)
